(kicad_pcb
	(version 20260206)
	(generator "pcbnew")
	(generator_version "10.0")
	(general
		(thickness 1.6)
		(legacy_teardrops no)
	)
	(paper "A4")
	(title_block
		(title "panther-plus-userver — 13130-1b_20150205.brd")
		(comment 1 "Honey Badger (Wiwynn) / footprint 894 of 1509 (DIMM1), pads 37-43 of 210")
	)
	(layers
		(0 "F.Cu" signal "TOP")
		(4 "In1.Cu" signal "L2")
		(6 "In2.Cu" signal "L3")
		(8 "In3.Cu" signal "L4")
		(10 "In4.Cu" signal "L5")
		(12 "In5.Cu" signal "L6")
		(14 "In6.Cu" signal "L7")
		(16 "In7.Cu" signal "L8")
		(18 "In8.Cu" signal "L9")
		(20 "In9.Cu" signal "L10")
		(22 "In10.Cu" signal "L11")
		(2 "B.Cu" signal "BOTTOM")
		(9 "F.Adhes" user "F.Adhesive")
		(11 "B.Adhes" user "B.Adhesive")
		(13 "F.Paste" user "Package Geometry/Pastemask Top")
		(15 "B.Paste" user "Package Geometry/Pastemask Bottom")
		(5 "F.SilkS" user "Ref Des/Silkscreen Top")
		(7 "B.SilkS" user "Ref Des/Silkscreen Bottom")
		(1 "F.Mask" user "Board Geometry/Soldermask Top")
		(3 "B.Mask" user "Board Geometry/Soldermask Bottom")
		(17 "Dwgs.User" user "User.Drawings")
		(19 "Cmts.User" user "User.Comments")
		(21 "Eco1.User" user "User.Eco1")
		(23 "Eco2.User" user "User.Eco2")
		(25 "Edge.Cuts" user "Board Geometry/Outline")
		(27 "Margin" user)
		(31 "F.CrtYd" user "Package Geometry/Place Bound Top")
		(29 "B.CrtYd" user "Package Geometry/Place Bound Bottom")
		(35 "F.Fab" user "Ref Des/Assembly Top")
		(33 "B.Fab" user "Ref Des/Assembly Bottom")
	)
	(footprint ""
		(layer "B.Cu")
		(at 158.500064 -66.699892 180)
		(property "Reference" "DIMM1"
			(at 0 0 0)
			(layer "B.SilkS")
			(hide yes)
			(effects
				(font
					(size 1.27 1.27)
				)
				(justify mirror)
			)
		)
		(property "Value" "DDR3-204P-142-COLAY-1-GP-U"
			(at 41.312338 -16.676878 180)
			(unlocked yes)
			(layer "B.Fab")
			(hide yes)
			(effects
				(font
					(size 1.016 1.016)
					(thickness 0.1524)
				)
				(justify mirror)
			)
		)
		(property "Device Type" "AS0A626-J8R6-7H-COLAY-1"
			(at 41.312338 -18.200878 180)
			(unlocked yes)
			(layer "B.Fab")
			(hide yes)
			(effects
				(font
					(size 1.016 1.016)
					(thickness 0.1524)
				)
				(justify mirror)
			)
		)
		(duplicate_pad_numbers_are_jumpers no)
		(pad "35" smd custom
			(at -21.450046 -4.100068)
			(size 0.1143 0.1143)
			(layers "B.Cu" "B.Mask" "B.Paste")
			(net "GND")
			(options
				(clearance outline)
				(anchor circle)
			)
			(primitives
				(gr_poly
					(pts
						(xy 0 -0.9017) (xy -0.03175 -0.89916) (xy -0.0635 -0.889) (xy -0.09144 -0.87376) (xy -0.11684 -0.85344)
						(xy -0.13716 -0.82804) (xy -0.1524 -0.8001) (xy -0.16256 -0.76835) (xy -0.1651 -0.7366) (xy -0.1651 -0.19685)
						(xy -0.17272 -0.18923) (xy -0.17907 -0.18034) (xy -0.18669 -0.17145) (xy -0.19177 -0.16256) (xy -0.19812 -0.15367)
						(xy -0.20828 -0.13335) (xy -0.21971 -0.10287) (xy -0.22225 -0.09271) (xy -0.22479 -0.08128) (xy -0.22606 -0.07112)
						(xy -0.2286 -0.05969) (xy -0.2286 -0.01651) (xy -0.22606 -0.00508) (xy -0.22479 0.00508) (xy -0.22225 0.01651)
						(xy -0.21971 0.02667) (xy -0.20828 0.05715) (xy -0.19812 0.07747) (xy -0.19177 0.08636) (xy -0.18669 0.09525)
						(xy -0.17907 0.10414) (xy -0.17272 0.11303) (xy -0.1651 0.12065) (xy -0.1651 0.7366) (xy -0.16256 0.76835)
						(xy -0.1524 0.8001) (xy -0.13716 0.82804) (xy -0.11684 0.85344) (xy -0.09144 0.87376) (xy -0.0635 0.889)
						(xy -0.03175 0.89916) (xy 0 0.9017) (xy 0.03175 0.89916) (xy 0.0635 0.889) (xy 0.09144 0.87376)
						(xy 0.11684 0.85344) (xy 0.13716 0.82804) (xy 0.1524 0.8001) (xy 0.16256 0.76835) (xy 0.1651 0.7366)
						(xy 0.1651 0.11938) (xy 0.17272 0.11176) (xy 0.19812 0.0762) (xy 0.2032 0.06604) (xy 0.20701 0.05715)
						(xy 0.21209 0.04699) (xy 0.2159 0.03683) (xy 0.21844 0.02667) (xy 0.22225 0.01524) (xy 0.22352 0.00508)
						(xy 0.22606 -0.00508) (xy 0.22733 -0.01651) (xy 0.22733 -0.02667) (xy 0.2286 -0.0381) (xy 0.22733 -0.04953)
						(xy 0.22733 -0.05969) (xy 0.22606 -0.07112) (xy 0.22352 -0.08128) (xy 0.22225 -0.09144) (xy 0.21844 -0.10287)
						(xy 0.2159 -0.11303) (xy 0.21209 -0.12319) (xy 0.20701 -0.13335) (xy 0.2032 -0.14224) (xy 0.19812 -0.1524)
						(xy 0.17272 -0.18796) (xy 0.1651 -0.19558) (xy 0.1651 -0.7366) (xy 0.16256 -0.76835) (xy 0.1524 -0.8001)
						(xy 0.13716 -0.82804) (xy 0.11684 -0.85344) (xy 0.09144 -0.87376) (xy 0.0635 -0.889) (xy 0.03175 -0.89916)
					)
					(width 0)
					(fill yes)
				)
			)
		)
		(pad "36" smd custom
			(at -21.150072 4.100068)
			(size 0.1143 0.1143)
			(layers "B.Cu" "B.Mask" "B.Paste")
			(net "M_A_DQ15")
			(options
				(clearance outline)
				(anchor circle)
			)
			(primitives
				(gr_poly
					(pts
						(xy 0 -0.9017) (xy -0.03175 -0.89916) (xy -0.0635 -0.889) (xy -0.09144 -0.87376) (xy -0.11684 -0.85344)
						(xy -0.13716 -0.82804) (xy -0.1524 -0.8001) (xy -0.16256 -0.76835) (xy -0.1651 -0.7366) (xy -0.1651 -0.11938)
						(xy -0.17272 -0.11176) (xy -0.19812 -0.0762) (xy -0.2032 -0.06604) (xy -0.20701 -0.05715) (xy -0.21209 -0.04699)
						(xy -0.2159 -0.03683) (xy -0.21844 -0.02667) (xy -0.22225 -0.01524) (xy -0.22352 -0.00508) (xy -0.22606 0.00508)
						(xy -0.22733 0.01651) (xy -0.22733 0.02667) (xy -0.2286 0.0381) (xy -0.22733 0.04953) (xy -0.22733 0.05969)
						(xy -0.22606 0.07112) (xy -0.22352 0.08128) (xy -0.22225 0.09144) (xy -0.21844 0.10287) (xy -0.2159 0.11303)
						(xy -0.21209 0.12319) (xy -0.20701 0.13335) (xy -0.2032 0.14224) (xy -0.19812 0.1524) (xy -0.17272 0.18796)
						(xy -0.1651 0.19558) (xy -0.1651 0.7366) (xy -0.16256 0.76835) (xy -0.1524 0.8001) (xy -0.13716 0.82804)
						(xy -0.11684 0.85344) (xy -0.09144 0.87376) (xy -0.0635 0.889) (xy -0.03175 0.89916) (xy 0 0.9017)
						(xy 0.03175 0.89916) (xy 0.0635 0.889) (xy 0.09144 0.87376) (xy 0.11684 0.85344) (xy 0.13716 0.82804)
						(xy 0.1524 0.8001) (xy 0.16256 0.76835) (xy 0.1651 0.7366) (xy 0.1651 0.19685) (xy 0.17272 0.18923)
						(xy 0.17907 0.18034) (xy 0.18669 0.17145) (xy 0.19177 0.16256) (xy 0.19812 0.15367) (xy 0.20828 0.13335)
						(xy 0.21971 0.10287) (xy 0.22225 0.09271) (xy 0.22479 0.08128) (xy 0.22606 0.07112) (xy 0.2286 0.05969)
						(xy 0.2286 0.01651) (xy 0.22606 0.00508) (xy 0.22479 -0.00508) (xy 0.22225 -0.01651) (xy 0.21971 -0.02667)
						(xy 0.20828 -0.05715) (xy 0.19812 -0.07747) (xy 0.19177 -0.08636) (xy 0.18669 -0.09525) (xy 0.17907 -0.10414)
						(xy 0.17272 -0.11303) (xy 0.1651 -0.12065) (xy 0.1651 -0.7366) (xy 0.16256 -0.76835) (xy 0.1524 -0.8001)
						(xy 0.13716 -0.82804) (xy 0.11684 -0.85344) (xy 0.09144 -0.87376) (xy 0.0635 -0.889) (xy 0.03175 -0.89916)
					)
					(width 0)
					(fill yes)
				)
			)
		)
		(pad "37" smd custom
			(at -20.850098 -4.100068)
			(size 0.1143 0.1143)
			(layers "B.Cu" "B.Mask" "B.Paste")
			(net "M_A_DQ16")
			(options
				(clearance outline)
				(anchor circle)
			)
			(primitives
				(gr_poly
					(pts
						(xy 0 -0.9017) (xy -0.03175 -0.89916) (xy -0.0635 -0.889) (xy -0.09144 -0.87376) (xy -0.11684 -0.85344)
						(xy -0.13716 -0.82804) (xy -0.1524 -0.8001) (xy -0.16256 -0.76835) (xy -0.1651 -0.7366) (xy -0.1651 -0.44958)
						(xy -0.17272 -0.44196) (xy -0.19812 -0.4064) (xy -0.2032 -0.39624) (xy -0.20701 -0.38735) (xy -0.21209 -0.37719)
						(xy -0.2159 -0.36703) (xy -0.21844 -0.35687) (xy -0.22225 -0.34544) (xy -0.22352 -0.33528) (xy -0.22606 -0.32512)
						(xy -0.22733 -0.31369) (xy -0.22733 -0.30353) (xy -0.2286 -0.2921) (xy -0.22733 -0.28067) (xy -0.22733 -0.27051)
						(xy -0.22606 -0.25908) (xy -0.22352 -0.24892) (xy -0.22225 -0.23876) (xy -0.21844 -0.22733) (xy -0.2159 -0.21717)
						(xy -0.21209 -0.20701) (xy -0.20701 -0.19685) (xy -0.2032 -0.18796) (xy -0.19812 -0.1778) (xy -0.17272 -0.14224)
						(xy -0.1651 -0.13462) (xy -0.1651 0.7366) (xy -0.16256 0.76835) (xy -0.1524 0.8001) (xy -0.13716 0.82804)
						(xy -0.11684 0.85344) (xy -0.09144 0.87376) (xy -0.0635 0.889) (xy -0.03175 0.89916) (xy 0 0.9017)
						(xy 0.03175 0.89916) (xy 0.0635 0.889) (xy 0.09144 0.87376) (xy 0.11684 0.85344) (xy 0.13716 0.82804)
						(xy 0.1524 0.8001) (xy 0.16256 0.76835) (xy 0.1651 0.7366) (xy 0.1651 -0.13462) (xy 0.17272 -0.14224)
						(xy 0.19812 -0.1778) (xy 0.2032 -0.18796) (xy 0.20701 -0.19685) (xy 0.21209 -0.20701) (xy 0.2159 -0.21717)
						(xy 0.21844 -0.22733) (xy 0.22225 -0.23876) (xy 0.22352 -0.24892) (xy 0.22606 -0.25908) (xy 0.22733 -0.27051)
						(xy 0.22733 -0.28067) (xy 0.2286 -0.2921) (xy 0.22733 -0.30353) (xy 0.22733 -0.31369) (xy 0.22606 -0.32512)
						(xy 0.22352 -0.33528) (xy 0.22225 -0.34544) (xy 0.21844 -0.35687) (xy 0.2159 -0.36703) (xy 0.21209 -0.37719)
						(xy 0.20701 -0.38735) (xy 0.2032 -0.39624) (xy 0.19812 -0.4064) (xy 0.17272 -0.44196) (xy 0.1651 -0.44958)
						(xy 0.1651 -0.7366) (xy 0.16256 -0.76835) (xy 0.1524 -0.8001) (xy 0.13716 -0.82804) (xy 0.11684 -0.85344)
						(xy 0.09144 -0.87376) (xy 0.0635 -0.889) (xy 0.03175 -0.89916)
					)
					(width 0)
					(fill yes)
				)
			)
		)
		(pad "38" smd custom
			(at -20.550124 4.100068)
			(size 0.1143 0.1143)
			(layers "B.Cu" "B.Mask" "B.Paste")
			(net "GND")
			(options
				(clearance outline)
				(anchor circle)
			)
			(primitives
				(gr_poly
					(pts
						(xy 0 -0.9017) (xy -0.03175 -0.89916) (xy -0.0635 -0.889) (xy -0.09144 -0.87376) (xy -0.11684 -0.85344)
						(xy -0.13716 -0.82804) (xy -0.1524 -0.8001) (xy -0.16256 -0.76835) (xy -0.1651 -0.7366) (xy -0.1651 0.13462)
						(xy -0.17272 0.14224) (xy -0.19812 0.1778) (xy -0.2032 0.18796) (xy -0.20701 0.19685) (xy -0.21209 0.20701)
						(xy -0.2159 0.21717) (xy -0.21844 0.22733) (xy -0.22225 0.23876) (xy -0.22352 0.24892) (xy -0.22606 0.25908)
						(xy -0.22733 0.27051) (xy -0.22733 0.28067) (xy -0.2286 0.2921) (xy -0.22733 0.30353) (xy -0.22733 0.31369)
						(xy -0.22606 0.32512) (xy -0.22352 0.33528) (xy -0.22225 0.34544) (xy -0.21844 0.35687) (xy -0.2159 0.36703)
						(xy -0.21209 0.37719) (xy -0.20701 0.38735) (xy -0.2032 0.39624) (xy -0.19812 0.4064) (xy -0.17272 0.44196)
						(xy -0.1651 0.44958) (xy -0.1651 0.7366) (xy -0.16256 0.76835) (xy -0.1524 0.8001) (xy -0.13716 0.82804)
						(xy -0.11684 0.85344) (xy -0.09144 0.87376) (xy -0.0635 0.889) (xy -0.03175 0.89916) (xy 0 0.9017)
						(xy 0.03175 0.89916) (xy 0.0635 0.889) (xy 0.09144 0.87376) (xy 0.11684 0.85344) (xy 0.13716 0.82804)
						(xy 0.1524 0.8001) (xy 0.16256 0.76835) (xy 0.1651 0.7366) (xy 0.1651 0.44958) (xy 0.17272 0.44196)
						(xy 0.19812 0.4064) (xy 0.2032 0.39624) (xy 0.20701 0.38735) (xy 0.21209 0.37719) (xy 0.2159 0.36703)
						(xy 0.21844 0.35687) (xy 0.22225 0.34544) (xy 0.22352 0.33528) (xy 0.22606 0.32512) (xy 0.22733 0.31369)
						(xy 0.22733 0.30353) (xy 0.2286 0.2921) (xy 0.22733 0.28067) (xy 0.22733 0.27051) (xy 0.22606 0.25908)
						(xy 0.22352 0.24892) (xy 0.22225 0.23876) (xy 0.21844 0.22733) (xy 0.2159 0.21717) (xy 0.21209 0.20701)
						(xy 0.20701 0.19685) (xy 0.2032 0.18796) (xy 0.19812 0.1778) (xy 0.17272 0.14224) (xy 0.1651 0.13462)
						(xy 0.1651 -0.7366) (xy 0.16256 -0.76835) (xy 0.1524 -0.8001) (xy 0.13716 -0.82804) (xy 0.11684 -0.85344)
						(xy 0.09144 -0.87376) (xy 0.0635 -0.889) (xy 0.03175 -0.89916)
					)
					(width 0)
					(fill yes)
				)
			)
		)
		(pad "39" smd custom
			(at -20.249896 -4.100068)
			(size 0.1143 0.1143)
			(layers "B.Cu" "B.Mask" "B.Paste")
			(net "M_A_DQ17")
			(options
				(clearance outline)
				(anchor circle)
			)
			(primitives
				(gr_poly
					(pts
						(xy 0 -0.9017) (xy -0.03175 -0.89916) (xy -0.0635 -0.889) (xy -0.09144 -0.87376) (xy -0.11684 -0.85344)
						(xy -0.13716 -0.82804) (xy -0.1524 -0.8001) (xy -0.16256 -0.76835) (xy -0.1651 -0.7366) (xy -0.1651 -0.19685)
						(xy -0.17272 -0.18923) (xy -0.17907 -0.18034) (xy -0.18669 -0.17145) (xy -0.19177 -0.16256) (xy -0.19812 -0.15367)
						(xy -0.20828 -0.13335) (xy -0.21971 -0.10287) (xy -0.22225 -0.09271) (xy -0.22479 -0.08128) (xy -0.22606 -0.07112)
						(xy -0.2286 -0.05969) (xy -0.2286 -0.01651) (xy -0.22606 -0.00508) (xy -0.22479 0.00508) (xy -0.22225 0.01651)
						(xy -0.21971 0.02667) (xy -0.20828 0.05715) (xy -0.19812 0.07747) (xy -0.19177 0.08636) (xy -0.18669 0.09525)
						(xy -0.17907 0.10414) (xy -0.17272 0.11303) (xy -0.1651 0.12065) (xy -0.1651 0.7366) (xy -0.16256 0.76835)
						(xy -0.1524 0.8001) (xy -0.13716 0.82804) (xy -0.11684 0.85344) (xy -0.09144 0.87376) (xy -0.0635 0.889)
						(xy -0.03175 0.89916) (xy 0 0.9017) (xy 0.03175 0.89916) (xy 0.0635 0.889) (xy 0.09144 0.87376)
						(xy 0.11684 0.85344) (xy 0.13716 0.82804) (xy 0.1524 0.8001) (xy 0.16256 0.76835) (xy 0.1651 0.7366)
						(xy 0.1651 0.11938) (xy 0.17272 0.11176) (xy 0.19812 0.0762) (xy 0.2032 0.06604) (xy 0.20701 0.05715)
						(xy 0.21209 0.04699) (xy 0.2159 0.03683) (xy 0.21844 0.02667) (xy 0.22225 0.01524) (xy 0.22352 0.00508)
						(xy 0.22606 -0.00508) (xy 0.22733 -0.01651) (xy 0.22733 -0.02667) (xy 0.2286 -0.0381) (xy 0.22733 -0.04953)
						(xy 0.22733 -0.05969) (xy 0.22606 -0.07112) (xy 0.22352 -0.08128) (xy 0.22225 -0.09144) (xy 0.21844 -0.10287)
						(xy 0.2159 -0.11303) (xy 0.21209 -0.12319) (xy 0.20701 -0.13335) (xy 0.2032 -0.14224) (xy 0.19812 -0.1524)
						(xy 0.17272 -0.18796) (xy 0.1651 -0.19558) (xy 0.1651 -0.7366) (xy 0.16256 -0.76835) (xy 0.1524 -0.8001)
						(xy 0.13716 -0.82804) (xy 0.11684 -0.85344) (xy 0.09144 -0.87376) (xy 0.0635 -0.889) (xy 0.03175 -0.89916)
					)
					(width 0)
					(fill yes)
				)
			)
		)
		(pad "40" smd custom
			(at -19.949922 4.100068)
			(size 0.1143 0.1143)
			(layers "B.Cu" "B.Mask" "B.Paste")
			(net "M_A_DQ20")
			(options
				(clearance outline)
				(anchor circle)
			)
			(primitives
				(gr_poly
					(pts
						(xy 0 -0.9017) (xy -0.03175 -0.89916) (xy -0.0635 -0.889) (xy -0.09144 -0.87376) (xy -0.11684 -0.85344)
						(xy -0.13716 -0.82804) (xy -0.1524 -0.8001) (xy -0.16256 -0.76835) (xy -0.1651 -0.7366) (xy -0.1651 -0.11938)
						(xy -0.17272 -0.11176) (xy -0.19812 -0.0762) (xy -0.2032 -0.06604) (xy -0.20701 -0.05715) (xy -0.21209 -0.04699)
						(xy -0.2159 -0.03683) (xy -0.21844 -0.02667) (xy -0.22225 -0.01524) (xy -0.22352 -0.00508) (xy -0.22606 0.00508)
						(xy -0.22733 0.01651) (xy -0.22733 0.02667) (xy -0.2286 0.0381) (xy -0.22733 0.04953) (xy -0.22733 0.05969)
						(xy -0.22606 0.07112) (xy -0.22352 0.08128) (xy -0.22225 0.09144) (xy -0.21844 0.10287) (xy -0.2159 0.11303)
						(xy -0.21209 0.12319) (xy -0.20701 0.13335) (xy -0.2032 0.14224) (xy -0.19812 0.1524) (xy -0.17272 0.18796)
						(xy -0.1651 0.19558) (xy -0.1651 0.7366) (xy -0.16256 0.76835) (xy -0.1524 0.8001) (xy -0.13716 0.82804)
						(xy -0.11684 0.85344) (xy -0.09144 0.87376) (xy -0.0635 0.889) (xy -0.03175 0.89916) (xy 0 0.9017)
						(xy 0.03175 0.89916) (xy 0.0635 0.889) (xy 0.09144 0.87376) (xy 0.11684 0.85344) (xy 0.13716 0.82804)
						(xy 0.1524 0.8001) (xy 0.16256 0.76835) (xy 0.1651 0.7366) (xy 0.1651 0.19685) (xy 0.17272 0.18923)
						(xy 0.17907 0.18034) (xy 0.18669 0.17145) (xy 0.19177 0.16256) (xy 0.19812 0.15367) (xy 0.20828 0.13335)
						(xy 0.21971 0.10287) (xy 0.22225 0.09271) (xy 0.22479 0.08128) (xy 0.22606 0.07112) (xy 0.2286 0.05969)
						(xy 0.2286 0.01651) (xy 0.22606 0.00508) (xy 0.22479 -0.00508) (xy 0.22225 -0.01651) (xy 0.21971 -0.02667)
						(xy 0.20828 -0.05715) (xy 0.19812 -0.07747) (xy 0.19177 -0.08636) (xy 0.18669 -0.09525) (xy 0.17907 -0.10414)
						(xy 0.17272 -0.11303) (xy 0.1651 -0.12065) (xy 0.1651 -0.7366) (xy 0.16256 -0.76835) (xy 0.1524 -0.8001)
						(xy 0.13716 -0.82804) (xy 0.11684 -0.85344) (xy 0.09144 -0.87376) (xy 0.0635 -0.889) (xy 0.03175 -0.89916)
					)
					(width 0)
					(fill yes)
				)
			)
		)
		(pad "41" smd custom
			(at -19.649948 -4.100068)
			(size 0.1143 0.1143)
			(layers "B.Cu" "B.Mask" "B.Paste")
			(net "GND")
			(options
				(clearance outline)
				(anchor circle)
			)
			(primitives
				(gr_poly
					(pts
						(xy 0 -0.9017) (xy -0.03175 -0.89916) (xy -0.0635 -0.889) (xy -0.09144 -0.87376) (xy -0.11684 -0.85344)
						(xy -0.13716 -0.82804) (xy -0.1524 -0.8001) (xy -0.16256 -0.76835) (xy -0.1651 -0.7366) (xy -0.1651 -0.44958)
						(xy -0.17272 -0.44196) (xy -0.19812 -0.4064) (xy -0.2032 -0.39624) (xy -0.20701 -0.38735) (xy -0.21209 -0.37719)
						(xy -0.2159 -0.36703) (xy -0.21844 -0.35687) (xy -0.22225 -0.34544) (xy -0.22352 -0.33528) (xy -0.22606 -0.32512)
						(xy -0.22733 -0.31369) (xy -0.22733 -0.30353) (xy -0.2286 -0.2921) (xy -0.22733 -0.28067) (xy -0.22733 -0.27051)
						(xy -0.22606 -0.25908) (xy -0.22352 -0.24892) (xy -0.22225 -0.23876) (xy -0.21844 -0.22733) (xy -0.2159 -0.21717)
						(xy -0.21209 -0.20701) (xy -0.20701 -0.19685) (xy -0.2032 -0.18796) (xy -0.19812 -0.1778) (xy -0.17272 -0.14224)
						(xy -0.1651 -0.13462) (xy -0.1651 0.7366) (xy -0.16256 0.76835) (xy -0.1524 0.8001) (xy -0.13716 0.82804)
						(xy -0.11684 0.85344) (xy -0.09144 0.87376) (xy -0.0635 0.889) (xy -0.03175 0.89916) (xy 0 0.9017)
						(xy 0.03175 0.89916) (xy 0.0635 0.889) (xy 0.09144 0.87376) (xy 0.11684 0.85344) (xy 0.13716 0.82804)
						(xy 0.1524 0.8001) (xy 0.16256 0.76835) (xy 0.1651 0.7366) (xy 0.1651 -0.13462) (xy 0.17272 -0.14224)
						(xy 0.19812 -0.1778) (xy 0.2032 -0.18796) (xy 0.20701 -0.19685) (xy 0.21209 -0.20701) (xy 0.2159 -0.21717)
						(xy 0.21844 -0.22733) (xy 0.22225 -0.23876) (xy 0.22352 -0.24892) (xy 0.22606 -0.25908) (xy 0.22733 -0.27051)
						(xy 0.22733 -0.28067) (xy 0.2286 -0.2921) (xy 0.22733 -0.30353) (xy 0.22733 -0.31369) (xy 0.22606 -0.32512)
						(xy 0.22352 -0.33528) (xy 0.22225 -0.34544) (xy 0.21844 -0.35687) (xy 0.2159 -0.36703) (xy 0.21209 -0.37719)
						(xy 0.20701 -0.38735) (xy 0.2032 -0.39624) (xy 0.19812 -0.4064) (xy 0.17272 -0.44196) (xy 0.1651 -0.44958)
						(xy 0.1651 -0.7366) (xy 0.16256 -0.76835) (xy 0.1524 -0.8001) (xy 0.13716 -0.82804) (xy 0.11684 -0.85344)
						(xy 0.09144 -0.87376) (xy 0.0635 -0.889) (xy 0.03175 -0.89916)
					)
					(width 0)
					(fill yes)
				)
			)
		)
	)
)
